(kicad_pcb
	(version 20260206)
	(generator "pcbnew")
	(generator_version "10.0")
	(general
		(thickness 1.6)
		(legacy_teardrops no)
	)
	(paper "A4")
	(title_block
		(title "baseboard — 13948-1b.1110WZS1818.brd")
		(comment 1 "Honey Badger (Wiwynn) / footprints 541-546 of 2523")
	)
	(layers
		(0 "F.Cu" signal "TOP")
		(4 "In1.Cu" signal "L2GND")
		(6 "In2.Cu" signal "L3")
		(8 "In3.Cu" signal "L4VCC")
		(10 "In4.Cu" signal "L5VCC")
		(12 "In5.Cu" signal "L6")
		(14 "In6.Cu" signal "L7GND")
		(2 "B.Cu" signal "BOTTOM")
		(9 "F.Adhes" user "F.Adhesive")
		(11 "B.Adhes" user "B.Adhesive")
		(13 "F.Paste" user "Package Geometry/Pastemask Top")
		(15 "B.Paste" user "Package Geometry/Pastemask Bottom")
		(5 "F.SilkS" user "Ref Des/Silkscreen Top")
		(7 "B.SilkS" user "Ref Des/Silkscreen Bottom")
		(1 "F.Mask" user "Board Geometry/Soldermask Top")
		(3 "B.Mask" user "Board Geometry/Soldermask Bottom")
		(17 "Dwgs.User" user "User.Drawings")
		(19 "Cmts.User" user "User.Comments")
		(21 "Eco1.User" user "User.Eco1")
		(23 "Eco2.User" user "User.Eco2")
		(25 "Edge.Cuts" user "Board Geometry/Outline")
		(27 "Margin" user)
		(31 "F.CrtYd" user "Package Geometry/Place Bound Top")
		(29 "B.CrtYd" user "Package Geometry/Place Bound Bottom")
		(35 "F.Fab" user "Ref Des/Assembly Top")
		(33 "B.Fab" user "Ref Des/Assembly Bottom")
	)
	(footprint ""
		(layer "F.Cu")
		(at 101.092 -221.488)
		(property "Reference" "R641"
			(at 0 0 0)
			(layer "F.SilkS")
			(hide yes)
			(effects
				(font
					(size 1.27 1.27)
				)
			)
		)
		(property "Value" "4K7R2F-GP"
			(at 0.064008 -3.993896 0)
			(unlocked yes)
			(layer "F.Fab")
			(hide yes)
			(effects
				(font
					(size 1.016 1.016)
					(thickness 0.1524)
				)
			)
		)
		(property "Device Type" "R402H16"
			(at 0.064008 -5.517896 0)
			(unlocked yes)
			(layer "F.Fab")
			(hide yes)
			(effects
				(font
					(size 1.016 1.016)
					(thickness 0.1524)
				)
			)
		)
		(duplicate_pad_numbers_are_jumpers no)
		(fp_line
			(start -0.508 -0.9398)
			(end -0.508 0.9398)
			(stroke
				(width 0.1524)
				(type default)
			)
			(layer "F.SilkS")
		)
		(fp_line
			(start 0.508 -0.9398)
			(end -0.508 -0.9398)
			(stroke
				(width 0.1524)
				(type default)
			)
			(layer "F.SilkS")
		)
		(fp_rect
			(start -0.508 0.9398)
			(end 0.508 -0.9398)
			(stroke
				(width 0)
				(type default)
			)
			(fill no)
			(layer "F.CrtYd")
		)
		(fp_rect
			(start -0.508 0.9398)
			(end 0.508 -0.9398)
			(stroke
				(width 0)
				(type default)
			)
			(fill no)
			(layer "F.Fab")
		)
		(pad "1" smd custom
			(at 0 -0.4445)
			(size 0.1397 0.1397)
			(layers "F.Cu" "F.Mask" "F.Paste")
			(net "IO_EXP_HDD_FAULT_A1")
			(options
				(clearance outline)
				(anchor circle)
			)
			(primitives
				(gr_poly
					(pts
						(arc
							(start -0.1778 -0.2794)
							(mid -0.249642 -0.249642)
							(end -0.2794 -0.1778)
						)
						(arc
							(start -0.2794 0.1778)
							(mid -0.249642 0.249642)
							(end -0.1778 0.2794)
						)
						(arc
							(start 0.1778 0.2794)
							(mid 0.249642 0.249642)
							(end 0.2794 0.1778)
						)
						(arc
							(start 0.2794 -0.1778)
							(mid 0.249642 -0.249642)
							(end 0.1778 -0.2794)
						)
					)
					(width 0)
					(fill yes)
				)
			)
		)
		(pad "2" smd custom
			(at 0 0.4445)
			(size 0.1397 0.1397)
			(layers "F.Cu" "F.Mask" "F.Paste")
			(net "GND")
			(options
				(clearance outline)
				(anchor circle)
			)
			(primitives
				(gr_poly
					(pts
						(arc
							(start -0.1778 -0.2794)
							(mid -0.249642 -0.249642)
							(end -0.2794 -0.1778)
						)
						(arc
							(start -0.2794 0.1778)
							(mid -0.249642 0.249642)
							(end -0.1778 0.2794)
						)
						(arc
							(start 0.1778 0.2794)
							(mid 0.249642 0.249642)
							(end 0.2794 0.1778)
						)
						(arc
							(start 0.2794 -0.1778)
							(mid 0.249642 -0.249642)
							(end 0.1778 -0.2794)
						)
					)
					(width 0)
					(fill yes)
				)
			)
		)
	)
	(footprint ""
		(layer "F.Cu")
		(at 79.888842 -128.951482 -90)
		(property "Reference" "SR786"
			(at 0 0 270)
			(layer "F.SilkS")
			(hide yes)
			(effects
				(font
					(size 1.27 1.27)
				)
			)
		)
		(property "Value" "4K75R2F-1-GP"
			(at 0.064008 -3.993896 270)
			(unlocked yes)
			(layer "F.Fab")
			(hide yes)
			(effects
				(font
					(size 1.016 1.016)
					(thickness 0.1524)
				)
			)
		)
		(property "Device Type" "R402H16"
			(at 0.064008 -5.517896 270)
			(unlocked yes)
			(layer "F.Fab")
			(hide yes)
			(effects
				(font
					(size 1.016 1.016)
					(thickness 0.1524)
				)
			)
		)
		(duplicate_pad_numbers_are_jumpers no)
		(fp_line
			(start -0.508 -0.9398)
			(end -0.508 0.9398)
			(stroke
				(width 0.1524)
				(type default)
			)
			(layer "F.SilkS")
		)
		(fp_line
			(start 0.508 -0.9398)
			(end -0.508 -0.9398)
			(stroke
				(width 0.1524)
				(type default)
			)
			(layer "F.SilkS")
		)
		(fp_rect
			(start -0.508 0.9398)
			(end 0.508 -0.9398)
			(stroke
				(width 0)
				(type default)
			)
			(fill no)
			(layer "F.CrtYd")
		)
		(fp_rect
			(start -0.508 0.9398)
			(end 0.508 -0.9398)
			(stroke
				(width 0)
				(type default)
			)
			(fill no)
			(layer "F.Fab")
		)
		(pad "1" smd custom
			(at 0 -0.4445 270)
			(size 0.1397 0.1397)
			(layers "F.Cu" "F.Mask" "F.Paste")
			(net "P1V8_E")
			(options
				(clearance outline)
				(anchor circle)
			)
			(primitives
				(gr_poly
					(pts
						(arc
							(start -0.1778 -0.2794)
							(mid -0.249642 -0.249642)
							(end -0.2794 -0.1778)
						)
						(arc
							(start -0.2794 0.1778)
							(mid -0.249642 0.249642)
							(end -0.1778 0.2794)
						)
						(arc
							(start 0.1778 0.2794)
							(mid 0.249642 0.249642)
							(end 0.2794 0.1778)
						)
						(arc
							(start 0.2794 -0.1778)
							(mid 0.249642 -0.249642)
							(end 0.1778 -0.2794)
						)
					)
					(width 0)
					(fill yes)
				)
			)
		)
		(pad "2" smd custom
			(at 0 0.4445 270)
			(size 0.1397 0.1397)
			(layers "F.Cu" "F.Mask" "F.Paste")
			(net "EXP_XM_NOR_CS_N")
			(options
				(clearance outline)
				(anchor circle)
			)
			(primitives
				(gr_poly
					(pts
						(arc
							(start -0.1778 -0.2794)
							(mid -0.249642 -0.249642)
							(end -0.2794 -0.1778)
						)
						(arc
							(start -0.2794 0.1778)
							(mid -0.249642 0.249642)
							(end -0.1778 0.2794)
						)
						(arc
							(start 0.1778 0.2794)
							(mid 0.249642 0.249642)
							(end 0.2794 0.1778)
						)
						(arc
							(start 0.2794 -0.1778)
							(mid 0.249642 -0.249642)
							(end 0.1778 -0.2794)
						)
					)
					(width 0)
					(fill yes)
				)
			)
		)
	)
	(footprint ""
		(layer "F.Cu")
		(at 318.008 -178.689 -90)
		(property "Reference" "R320"
			(at 0 0 270)
			(layer "F.SilkS")
			(hide yes)
			(effects
				(font
					(size 1.27 1.27)
				)
			)
		)
		(property "Value" "0R2J-2-GP"
			(at 0.064008 -3.993896 270)
			(unlocked yes)
			(layer "F.Fab")
			(hide yes)
			(effects
				(font
					(size 1.016 1.016)
					(thickness 0.1524)
				)
			)
		)
		(property "Device Type" "R402H16"
			(at 0.064008 -5.517896 270)
			(unlocked yes)
			(layer "F.Fab")
			(hide yes)
			(effects
				(font
					(size 1.016 1.016)
					(thickness 0.1524)
				)
			)
		)
		(duplicate_pad_numbers_are_jumpers no)
		(fp_line
			(start -0.508 -0.9398)
			(end -0.508 0.9398)
			(stroke
				(width 0.1524)
				(type default)
			)
			(layer "F.SilkS")
		)
		(fp_line
			(start 0.508 -0.9398)
			(end -0.508 -0.9398)
			(stroke
				(width 0.1524)
				(type default)
			)
			(layer "F.SilkS")
		)
		(fp_rect
			(start -0.508 0.9398)
			(end 0.508 -0.9398)
			(stroke
				(width 0)
				(type default)
			)
			(fill no)
			(layer "F.CrtYd")
		)
		(fp_rect
			(start -0.508 0.9398)
			(end 0.508 -0.9398)
			(stroke
				(width 0)
				(type default)
			)
			(fill no)
			(layer "F.Fab")
		)
		(pad "1" smd custom
			(at 0 -0.4445 270)
			(size 0.1397 0.1397)
			(layers "F.Cu" "F.Mask" "F.Paste")
			(net "ADC_P1V5_C")
			(options
				(clearance outline)
				(anchor circle)
			)
			(primitives
				(gr_poly
					(pts
						(arc
							(start -0.1778 -0.2794)
							(mid -0.249642 -0.249642)
							(end -0.2794 -0.1778)
						)
						(arc
							(start -0.2794 0.1778)
							(mid -0.249642 0.249642)
							(end -0.1778 0.2794)
						)
						(arc
							(start 0.1778 0.2794)
							(mid 0.249642 0.249642)
							(end 0.2794 0.1778)
						)
						(arc
							(start 0.2794 -0.1778)
							(mid 0.249642 -0.249642)
							(end 0.1778 -0.2794)
						)
					)
					(width 0)
					(fill yes)
				)
			)
		)
		(pad "2" smd custom
			(at 0 0.4445 270)
			(size 0.1397 0.1397)
			(layers "F.Cu" "F.Mask" "F.Paste")
			(net "ADC_P1V5_C_BMC")
			(options
				(clearance outline)
				(anchor circle)
			)
			(primitives
				(gr_poly
					(pts
						(arc
							(start -0.1778 -0.2794)
							(mid -0.249642 -0.249642)
							(end -0.2794 -0.1778)
						)
						(arc
							(start -0.2794 0.1778)
							(mid -0.249642 0.249642)
							(end -0.1778 0.2794)
						)
						(arc
							(start 0.1778 0.2794)
							(mid 0.249642 0.249642)
							(end 0.2794 0.1778)
						)
						(arc
							(start 0.2794 -0.1778)
							(mid 0.249642 -0.249642)
							(end 0.1778 -0.2794)
						)
					)
					(width 0)
					(fill yes)
				)
			)
		)
	)
	(footprint ""
		(layer "F.Cu")
		(at 264.033 -32.639 -90)
		(property "Reference" "PR56"
			(at 0 0 270)
			(layer "F.SilkS")
			(hide yes)
			(effects
				(font
					(size 1.27 1.27)
				)
			)
		)
		(property "Value" "0R2J-2-GP"
			(at 0.064008 -3.993896 270)
			(unlocked yes)
			(layer "F.Fab")
			(hide yes)
			(effects
				(font
					(size 1.016 1.016)
					(thickness 0.1524)
				)
			)
		)
		(property "Device Type" "R402H16"
			(at 0.064008 -5.517896 270)
			(unlocked yes)
			(layer "F.Fab")
			(hide yes)
			(effects
				(font
					(size 1.016 1.016)
					(thickness 0.1524)
				)
			)
		)
		(duplicate_pad_numbers_are_jumpers no)
		(fp_line
			(start -0.508 -0.9398)
			(end -0.508 0.9398)
			(stroke
				(width 0.1524)
				(type default)
			)
			(layer "F.SilkS")
		)
		(fp_line
			(start 0.508 -0.9398)
			(end -0.508 -0.9398)
			(stroke
				(width 0.1524)
				(type default)
			)
			(layer "F.SilkS")
		)
		(fp_rect
			(start -0.508 0.9398)
			(end 0.508 -0.9398)
			(stroke
				(width 0)
				(type default)
			)
			(fill no)
			(layer "F.CrtYd")
		)
		(fp_rect
			(start -0.508 0.9398)
			(end 0.508 -0.9398)
			(stroke
				(width 0)
				(type default)
			)
			(fill no)
			(layer "F.Fab")
		)
		(pad "1" smd custom
			(at 0 -0.4445 270)
			(size 0.1397 0.1397)
			(layers "F.Cu" "F.Mask" "F.Paste")
			(net "P1V8_STBY_ROVP")
			(options
				(clearance outline)
				(anchor circle)
			)
			(primitives
				(gr_poly
					(pts
						(arc
							(start -0.1778 -0.2794)
							(mid -0.249642 -0.249642)
							(end -0.2794 -0.1778)
						)
						(arc
							(start -0.2794 0.1778)
							(mid -0.249642 0.249642)
							(end -0.1778 0.2794)
						)
						(arc
							(start 0.1778 0.2794)
							(mid 0.249642 0.249642)
							(end 0.2794 0.1778)
						)
						(arc
							(start 0.2794 -0.1778)
							(mid 0.249642 -0.249642)
							(end 0.1778 -0.2794)
						)
					)
					(width 0)
					(fill yes)
				)
			)
		)
		(pad "2" smd custom
			(at 0 0.4445 270)
			(size 0.1397 0.1397)
			(layers "F.Cu" "F.Mask" "F.Paste")
			(net "AGND_P1V8_STBY")
			(options
				(clearance outline)
				(anchor circle)
			)
			(primitives
				(gr_poly
					(pts
						(arc
							(start -0.1778 -0.2794)
							(mid -0.249642 -0.249642)
							(end -0.2794 -0.1778)
						)
						(arc
							(start -0.2794 0.1778)
							(mid -0.249642 0.249642)
							(end -0.1778 0.2794)
						)
						(arc
							(start 0.1778 0.2794)
							(mid 0.249642 0.249642)
							(end 0.2794 0.1778)
						)
						(arc
							(start 0.2794 -0.1778)
							(mid 0.249642 -0.249642)
							(end 0.1778 -0.2794)
						)
					)
					(width 0)
					(fill yes)
				)
			)
		)
	)
	(footprint ""
		(layer "F.Cu")
		(at 95.70847 -110.617 -90)
		(property "Reference" "SR739"
			(at 0 0 270)
			(layer "F.SilkS")
			(hide yes)
			(effects
				(font
					(size 1.27 1.27)
				)
			)
		)
		(property "Value" "2K2R2F-GP"
			(at 0.064008 -3.993896 270)
			(unlocked yes)
			(layer "F.Fab")
			(hide yes)
			(effects
				(font
					(size 1.016 1.016)
					(thickness 0.1524)
				)
			)
		)
		(property "Device Type" "R402H16"
			(at 0.064008 -5.517896 270)
			(unlocked yes)
			(layer "F.Fab")
			(hide yes)
			(effects
				(font
					(size 1.016 1.016)
					(thickness 0.1524)
				)
			)
		)
		(duplicate_pad_numbers_are_jumpers no)
		(fp_line
			(start -0.508 -0.9398)
			(end -0.508 0.9398)
			(stroke
				(width 0.1524)
				(type default)
			)
			(layer "F.SilkS")
		)
		(fp_line
			(start 0.508 -0.9398)
			(end -0.508 -0.9398)
			(stroke
				(width 0.1524)
				(type default)
			)
			(layer "F.SilkS")
		)
		(fp_rect
			(start -0.508 0.9398)
			(end 0.508 -0.9398)
			(stroke
				(width 0)
				(type default)
			)
			(fill no)
			(layer "F.CrtYd")
		)
		(fp_rect
			(start -0.508 0.9398)
			(end 0.508 -0.9398)
			(stroke
				(width 0)
				(type default)
			)
			(fill no)
			(layer "F.Fab")
		)
		(pad "1" smd custom
			(at 0 -0.4445 270)
			(size 0.1397 0.1397)
			(layers "F.Cu" "F.Mask" "F.Paste")
			(net "EXP_I2C_SDA_2")
			(options
				(clearance outline)
				(anchor circle)
			)
			(primitives
				(gr_poly
					(pts
						(arc
							(start -0.1778 -0.2794)
							(mid -0.249642 -0.249642)
							(end -0.2794 -0.1778)
						)
						(arc
							(start -0.2794 0.1778)
							(mid -0.249642 0.249642)
							(end -0.1778 0.2794)
						)
						(arc
							(start 0.1778 0.2794)
							(mid 0.249642 0.249642)
							(end 0.2794 0.1778)
						)
						(arc
							(start 0.2794 -0.1778)
							(mid 0.249642 -0.249642)
							(end 0.1778 -0.2794)
						)
					)
					(width 0)
					(fill yes)
				)
			)
		)
		(pad "2" smd custom
			(at 0 0.4445 270)
			(size 0.1397 0.1397)
			(layers "F.Cu" "F.Mask" "F.Paste")
			(net "P1V8_E")
			(options
				(clearance outline)
				(anchor circle)
			)
			(primitives
				(gr_poly
					(pts
						(arc
							(start -0.1778 -0.2794)
							(mid -0.249642 -0.249642)
							(end -0.2794 -0.1778)
						)
						(arc
							(start -0.2794 0.1778)
							(mid -0.249642 0.249642)
							(end -0.1778 0.2794)
						)
						(arc
							(start 0.1778 0.2794)
							(mid 0.249642 0.249642)
							(end 0.2794 0.1778)
						)
						(arc
							(start 0.2794 -0.1778)
							(mid 0.249642 -0.249642)
							(end 0.1778 -0.2794)
						)
					)
					(width 0)
					(fill yes)
				)
			)
		)
	)
	(footprint ""
		(layer "F.Cu")
		(at 144.907 -96.647 90)
		(property "Reference" "SC1176"
			(at 0 0 90)
			(layer "F.SilkS")
			(hide yes)
			(effects
				(font
					(size 1.27 1.27)
				)
			)
		)
		(property "Value" "SC100U6D3V0MX-2GP"
			(at -0.00254 -4.78536 90)
			(unlocked yes)
			(layer "F.Fab")
			(hide yes)
			(effects
				(font
					(size 1.016 1.016)
					(thickness 0.1524)
				)
			)
		)
		(property "Device Type" "C1210H107"
			(at -0.00254 -6.38048 90)
			(unlocked yes)
			(layer "F.Fab")
			(hide yes)
			(effects
				(font
					(size 1.016 1.016)
					(thickness 0.1524)
				)
			)
		)
		(duplicate_pad_numbers_are_jumpers no)
		(fp_line
			(start 1.5748 -2.3368)
			(end -1.5748 -2.3368)
			(stroke
				(width 0.1524)
				(type default)
			)
			(layer "F.SilkS")
		)
		(fp_line
			(start -1.5748 -2.3368)
			(end -1.5748 -0.762)
			(stroke
				(width 0.1524)
				(type default)
			)
			(layer "F.SilkS")
		)
		(fp_line
			(start 1.5748 -0.762)
			(end 1.5748 -2.3368)
			(stroke
				(width 0.1524)
				(type default)
			)
			(layer "F.SilkS")
		)
		(fp_line
			(start -1.5748 0.762)
			(end -1.5748 2.3368)
			(stroke
				(width 0.1524)
				(type default)
			)
			(layer "F.SilkS")
		)
		(fp_line
			(start 1.5748 2.3368)
			(end 1.5748 0.762)
			(stroke
				(width 0.1524)
				(type default)
			)
			(layer "F.SilkS")
		)
		(fp_line
			(start -1.5748 2.3368)
			(end 1.5748 2.3368)
			(stroke
				(width 0.1524)
				(type default)
			)
			(layer "F.SilkS")
		)
		(fp_rect
			(start -1.651 2.413)
			(end 1.651 -2.413)
			(stroke
				(width 0)
				(type default)
			)
			(fill no)
			(layer "F.CrtYd")
		)
		(fp_poly
			(pts
				(xy 1.651 2.413) (xy 1.651 -2.413) (xy -1.651 -2.413) (xy -1.651 2.413)
			)
			(stroke
				(width 0)
				(type default)
			)
			(fill no)
			(layer "F.Fab")
		)
		(pad "1" smd rect
			(at 0 -1.4732 90)
			(size 2.794 1.397)
			(layers "F.Cu" "F.Mask" "F.Paste")
			(net "GND")
		)
		(pad "2" smd rect
			(at 0 1.4732 90)
			(size 2.794 1.397)
			(layers "F.Cu" "F.Mask" "F.Paste")
			(net "GB_VDDA")
		)
	)
)
